G04 ================== begin FILE IDENTIFICATION RECORD ==================*
G04 Layout Name:  9054_F0T_PDB_BD_GPU_F_V04_1213_1550.brd*
G04 Film Name:    pmb*
G04 File Format:  Gerber RS274X*
G04 File Origin:  Cadence Allegro 17.2-S081*
G04 Origin Date:  Wed Dec 28 10:19:02 2022*
G04 *
G04 Layer:  DRAWING FORMAT/TITLE_BLOCK_A*
G04 Layer:  VIA CLASS/PASTEMASK_BOTTOM*
G04 Layer:  PIN/PASTEMASK_BOTTOM*
G04 Layer:  PACKAGE GEOMETRY/PASTEMASK_BOTTOM*
G04 Layer:  MANUFACTURING/PHOTOPLOT_OUTLINE*
G04 Layer:  DRAWING FORMAT/TITLE_BLOCK*
G04 Layer:  DRAWING FORMAT/TITLE_DATA_PMB*
G04 *
G04 Offset:    (0.00 0.00)*
G04 Mirror:    No*
G04 Mode:      Positive*
G04 Rotation:  0*
G04 FullContactRelief:  No*
G04 UndefLineWidth:     6.00*
G04 ================== end FILE IDENTIFICATION RECORD ====================*
%FSLAX25Y25*MOIN*%
%IR0*IPPOS*OFA0.00000B0.00000*MIA0B0*SFA1.00000B1.00000*%
%ADD22C,.02*%
%ADD43R,.13X.095*%
%AMMACRO49*
4,1,5,-.07185,-.1063,
.07185,-.1063,
.07185,.09252,
.05807,.1063,
-.07185,.1063,
-.07185,-.1063,
0.0*
%
%ADD49MACRO49*%
%ADD53C,.061*%
%ADD12C,.07*%
%ADD11C,.026*%
%ADD40R,.059X.134*%
%ADD47C,.066*%
%ADD10C,.039*%
%ADD13R,.07X.07*%
%ADD46R,.066X.066*%
%AMMACRO19*
4,1,28,-.00748,.00052,
-.00984,.00052,
-.00984,.00603,
-.009782,.006705,
-.009607,.007359,
-.009321,.007974,
-.008933,.008529,
-.008455,.009009,
-.0079,.009398,
-.007286,.009685,
-.006632,.009861,
-.005957,.00992,
-.00591,.00992,
.00591,.00992,
.006585,.009869,
.007242,.009701,
.007859,.009421,
.008418,.009039,
.008903,.008565,
.009297,.008015,
.009591,.007404,
.009773,.006751,
.00984,.006077,
.00984,.00603,
.00984,.00052,
.00748,.00052,
.00748,-.00991,
-.00748,-.00991,
-.00748,.00052,
0.0*
%
%ADD19MACRO19*%
%AMMACRO35*
4,1,28,.00052,.00748,
.00052,.00984,
.00603,.00984,
.006705,.009782,
.007359,.009607,
.007974,.009321,
.008529,.008933,
.009009,.008455,
.009398,.0079,
.009685,.007286,
.009861,.006632,
.00992,.005957,
.00992,.00591,
.00992,-.00591,
.009869,-.006585,
.009701,-.007242,
.009421,-.007859,
.009039,-.008418,
.008565,-.008903,
.008015,-.009297,
.007404,-.009591,
.006751,-.009773,
.006077,-.00984,
.00603,-.00984,
.00052,-.00984,
.00052,-.00748,
-.00991,-.00748,
-.00991,.00748,
.00052,.00748,
0.0*
%
%ADD35MACRO35*%
%AMMACRO18*
4,1,28,-.00748,-.00051,
-.00984,-.00051,
-.00984,-.00602,
-.009782,-.006695,
-.009607,-.007349,
-.009321,-.007964,
-.008933,-.008519,
-.008455,-.008998,
-.0079,-.009388,
-.007287,-.009675,
-.006632,-.009851,
-.005958,-.00991,
-.00591,-.00991,
.00591,-.00991,
.006585,-.009859,
.007242,-.009691,
.007859,-.009411,
.008418,-.009029,
.008903,-.008555,
.009297,-.008005,
.00959,-.007394,
.009773,-.006742,
.00984,-.006068,
.00984,-.00602,
.00984,-.00051,
.00748,-.00051,
.00748,.00992,
-.00748,.00992,
-.00748,-.00051,
0.0*
%
%ADD18MACRO18*%
%AMMACRO34*
4,1,28,-.00051,.00748,
-.00051,.00984,
-.00602,.00984,
-.006695,.009782,
-.007349,.009607,
-.007964,.009321,
-.008519,.008933,
-.008998,.008455,
-.009388,.0079,
-.009675,.007287,
-.009851,.006632,
-.00991,.005958,
-.00991,.00591,
-.00991,-.00591,
-.009859,-.006585,
-.009691,-.007242,
-.009411,-.007859,
-.009029,-.008418,
-.008555,-.008903,
-.008005,-.009297,
-.007394,-.00959,
-.006742,-.009773,
-.006068,-.00984,
-.00602,-.00984,
-.00051,-.00984,
-.00051,-.00748,
.00992,-.00748,
.00992,.00748,
-.00051,.00748,
0.0*
%
%ADD34MACRO34*%
%ADD37R,.11X.22*%
%ADD32R,.03X.011*%
%ADD38O,.033X.012*%
%ADD31R,.011X.03*%
%ADD39O,.012X.033*%
%ADD48R,.032X.022*%
%ADD41R,.04X.05*%
%ADD21R,.02X.018*%
%ADD29R,.028X.011*%
%ADD20R,.034X.032*%
%ADD36R,.063X.04*%
%ADD30R,.011X.028*%
%ADD50R,.024X.017*%
%AMMACRO28*
4,1,5,.07185,.1063,
-.07185,.1063,
-.07185,-.09252,
-.05807,-.1063,
.07185,-.1063,
.07185,.1063,
0.0*
%
%ADD28MACRO28*%
%ADD51R,.017X.024*%
%ADD42R,.135X.128*%
%ADD14R,.032X.028*%
%ADD24R,.046X.015*%
%ADD15R,.028X.032*%
%ADD25R,.054X.044*%
%ADD45C,.315*%
%ADD44R,.062X.046*%
%ADD23R,.044X.054*%
%ADD52R,.059X.014*%
%ADD33R,.046X.062*%
%AMMACRO27*
4,1,28,-.00052,-.00748,
-.00052,-.00984,
-.00603,-.00984,
-.006705,-.009782,
-.007359,-.009607,
-.007974,-.009321,
-.008529,-.008933,
-.009009,-.008455,
-.009398,-.0079,
-.009685,-.007286,
-.009861,-.006632,
-.00992,-.005957,
-.00992,-.00591,
-.00992,.00591,
-.009869,.006585,
-.009701,.007242,
-.009421,.007859,
-.009039,.008418,
-.008565,.008903,
-.008015,.009297,
-.007404,.009591,
-.006751,.009773,
-.006077,.00984,
-.00603,.00984,
-.00052,.00984,
-.00052,.00748,
.00991,.00748,
.00991,-.00748,
-.00052,-.00748,
0.0*
%
%ADD27MACRO27*%
%AMMACRO17*
4,1,28,.00748,-.00052,
.00984,-.00052,
.00984,-.00603,
.009782,-.006705,
.009607,-.007359,
.009321,-.007974,
.008933,-.008529,
.008455,-.009009,
.0079,-.009398,
.007286,-.009685,
.006632,-.009861,
.005957,-.00992,
.00591,-.00992,
-.00591,-.00992,
-.006585,-.009869,
-.007242,-.009701,
-.007859,-.009421,
-.008418,-.009039,
-.008903,-.008565,
-.009297,-.008015,
-.009591,-.007404,
-.009773,-.006751,
-.00984,-.006077,
-.00984,-.00603,
-.00984,-.00052,
-.00748,-.00052,
-.00748,.00991,
.00748,.00991,
.00748,-.00052,
0.0*
%
%ADD17MACRO17*%
%AMMACRO26*
4,1,28,.00051,-.00748,
.00051,-.00984,
.00602,-.00984,
.006695,-.009782,
.007349,-.009607,
.007964,-.009321,
.008519,-.008933,
.008998,-.008455,
.009388,-.0079,
.009675,-.007287,
.009851,-.006632,
.00991,-.005958,
.00991,-.00591,
.00991,.00591,
.009859,.006585,
.009691,.007242,
.009411,.007859,
.009029,.008418,
.008555,.008903,
.008005,.009297,
.007394,.00959,
.006742,.009773,
.006068,.00984,
.00602,.00984,
.00051,.00984,
.00051,.00748,
-.00992,.00748,
-.00992,-.00748,
.00051,-.00748,
0.0*
%
%ADD26MACRO26*%
%AMMACRO16*
4,1,28,.00748,.00051,
.00984,.00051,
.00984,.00602,
.009782,.006695,
.009607,.007349,
.009321,.007964,
.008933,.008519,
.008455,.008998,
.0079,.009388,
.007287,.009675,
.006632,.009851,
.005958,.00991,
.00591,.00991,
-.00591,.00991,
-.006585,.009859,
-.007242,.009691,
-.007859,.009411,
-.008418,.009029,
-.008903,.008555,
-.009297,.008005,
-.00959,.007394,
-.009773,.006742,
-.00984,.006068,
-.00984,.00602,
-.00984,.00051,
-.00748,.00051,
-.00748,-.00992,
.00748,-.00992,
.00748,.00051,
0.0*
%
%ADD16MACRO16*%
%ADD54C,.006*%
G75*
%LPD*%
G75*
G54D10*
X102422Y604336D03*
X590000Y208500D03*
X1286300Y331400D03*
X1717750Y599624D03*
G54D20*
X428100Y178900D03*
Y170300D03*
Y223300D03*
Y214700D03*
X1334100Y158800D03*
Y150200D03*
Y203200D03*
Y194600D03*
G54D11*
X137355Y120500D03*
X134600Y150000D03*
Y134000D03*
X156785Y101285D03*
X205061Y67500D03*
X211425Y106075D03*
X205061Y93000D03*
X200600Y109059D03*
X210925Y115575D03*
X317000Y58000D03*
X321500Y66500D03*
X332500Y63300D03*
X396216Y46875D03*
X412000Y175000D03*
X417300Y185200D03*
X418500Y229600D03*
X412000Y219300D03*
X441938Y132100D03*
Y309700D03*
X458946Y341216D03*
X455946Y357216D03*
X465946Y357016D03*
X471946Y341216D03*
X484446D03*
X517409Y322000D03*
X506309Y329000D03*
Y322000D03*
X517410Y329000D03*
X551430Y132400D03*
X580184Y117800D03*
X586184Y111800D03*
X580184Y105800D03*
X562830Y140300D03*
X574230Y132400D03*
X563007Y251677D03*
X581562Y272005D03*
X562830Y266500D03*
X571542Y289065D03*
X577808Y278085D03*
X594000Y257000D03*
X602200Y253200D03*
X622003Y297500D03*
X641500Y232000D03*
X626026Y266657D03*
X629684Y260000D03*
X630684Y269000D03*
X627184Y287500D03*
X629684Y300000D03*
X627684Y293425D03*
X635600Y309416D03*
X657784Y40500D03*
Y96000D03*
X676638Y230894D03*
X666000Y241000D03*
X681684Y230820D03*
X676756Y257572D03*
X677184Y267000D03*
X680100Y297600D03*
X672242Y294442D03*
X673800Y289400D03*
X672200Y283700D03*
X675100Y304500D03*
X702223Y197419D03*
X689684Y230762D03*
X698497Y257727D03*
X707980Y252376D03*
X713184Y298500D03*
X695734Y296950D03*
X687854Y299000D03*
X720100Y185000D03*
X725000Y292500D03*
X721214Y284666D03*
X758600Y185000D03*
X788100Y383000D03*
X882660Y350840D03*
X885100Y361500D03*
X974500Y185000D03*
X978600Y310955D03*
X1013000Y185000D03*
X1034360Y254000D03*
X1041840Y253760D03*
X1040539Y266826D03*
X1045337Y298773D03*
X1021414Y355979D03*
X1017300Y385600D03*
X1041400Y368600D03*
X1074500Y43500D03*
Y99000D03*
X1066550Y255050D03*
X1072286Y294922D03*
X1064032Y294958D03*
X1050500Y336500D03*
X1078100Y253500D03*
X1082850Y256750D03*
X1086850Y265750D03*
X1087100Y260500D03*
X1089937Y271255D03*
X1077300Y294000D03*
X1085100Y285000D03*
X1090500Y290500D03*
X1085528Y294428D03*
X1101200Y355600D03*
X1131700Y263000D03*
X1127100Y242500D03*
X1132600Y252000D03*
X1134600Y258575D03*
X1136258Y285343D03*
X1132600Y292000D03*
X1133459Y277272D03*
X1131600Y283000D03*
X1120000Y317500D03*
Y323000D03*
X1113000Y339000D03*
X1133000Y353240D03*
X1140100Y254500D03*
X1160200Y299800D03*
X1152647Y294655D03*
X1166000Y352500D03*
X1182100Y105800D03*
X1167371Y296240D03*
X1182409Y286245D03*
X1180808Y297945D03*
X1176000Y350000D03*
X1168500Y344425D03*
X1210500Y132400D03*
Y265600D03*
X1225930Y359148D03*
X1244874Y330000D03*
X1255975D03*
X1242930Y359148D03*
X1255975Y337000D03*
X1260340Y359284D03*
X1286113Y378312D03*
X1320346Y112300D03*
X1345500Y165500D03*
X1342900Y209600D03*
X1320346Y289900D03*
X1350000Y154800D03*
X1350100Y199250D03*
X1406230Y15076D03*
X1400230Y21076D03*
X1412230D03*
X1494000Y59500D03*
X1490000Y80500D03*
X1499228Y74500D03*
X1490228Y66500D03*
X1505100Y64500D03*
X1551000Y96500D03*
X1567500Y67000D03*
X1618800Y76700D03*
X1597100Y145000D03*
Y126000D03*
X1625370Y103940D03*
X1632336Y109117D03*
X1631323Y115140D03*
X1636400Y127429D03*
X1641932Y122969D03*
X1643217Y135054D03*
X1635000Y142500D03*
X1634500Y147500D03*
X1647500Y140000D03*
X1635000Y152925D03*
X1650117Y180000D03*
X1622100Y155931D03*
X1630075Y158000D03*
X1641500Y178000D03*
X1635000Y164500D03*
X1657050Y116760D03*
X1669800Y120400D03*
X1675800D03*
X1656657Y127365D03*
X1651325Y125076D03*
X1673000Y141000D03*
Y146500D03*
X1676350Y160251D03*
X1673250Y151750D03*
X1674500Y175000D03*
X1680000D03*
X1666500Y178500D03*
X1677000Y169500D03*
X1680500Y165000D03*
X1661000Y178500D03*
X1672050Y181550D03*
X1668075Y189500D03*
X1679176Y194760D03*
X1664000Y202500D03*
X1658500Y183000D03*
X1652500Y185000D03*
X1677500Y182000D03*
X1654000Y192500D03*
X1660000Y193500D03*
X1706100Y92000D03*
X1701350Y114250D03*
X1696600Y119000D03*
X1685100Y127500D03*
X1702525Y129500D03*
X1692600Y135975D03*
X1688100Y145560D03*
X1685000Y133000D03*
X1685976Y153500D03*
X1688100Y173060D03*
Y162060D03*
X1709600Y158000D03*
X1682000Y160000D03*
X1701100Y182000D03*
X1688100Y184220D03*
X1702075Y205500D03*
X1719075Y107016D03*
X1721685Y95940D03*
X1727200Y104500D03*
X1721000Y142525D03*
X1714100Y144925D03*
X1729411Y143661D03*
X1727100Y164280D03*
X1715525Y168500D03*
X1722063Y156962D03*
X1726099Y153000D03*
X1720100Y179500D03*
X1729411Y159161D03*
X1733500Y173760D03*
X1738740Y191500D03*
X1759600Y114500D03*
X1767425Y107000D03*
X1761600Y124524D03*
X1764000Y142525D03*
X1770575Y137000D03*
X1763075Y178900D03*
X1767075Y155484D03*
X1769476Y168500D03*
X1743500Y181000D03*
X1742500Y198000D03*
X1747925Y204000D03*
X1743500Y187500D03*
X1762454Y320347D03*
X1769300Y329400D03*
X1747235Y355989D03*
X1769300Y340600D03*
X1769692Y334649D03*
X1767700Y346200D03*
X1747235Y363689D03*
Y371389D03*
X1773000Y142525D03*
X1773500Y129500D03*
X1773000Y158000D03*
X1772600Y177300D03*
X1795600Y308000D03*
X1817500Y188000D03*
X1811500Y186000D03*
X1847164Y419238D03*
X1842164Y432338D03*
X1847164Y430568D03*
X1852164Y435538D03*
X1837164Y428238D03*
G54D30*
X595857Y262514D03*
X617511D03*
Y289486D03*
X595857D03*
X1144773Y262514D03*
Y289486D03*
X1166427Y262514D03*
Y289486D03*
G54D21*
X422000Y169925D03*
Y173075D03*
Y214425D03*
Y217575D03*
X1340100Y150125D03*
Y153275D03*
X1340600Y194325D03*
Y197475D03*
G54D12*
X166785Y200472D03*
Y280472D03*
Y360472D03*
Y440472D03*
Y520472D03*
X243785Y200472D03*
Y280472D03*
Y360472D03*
Y440472D03*
Y520472D03*
X1488500Y200472D03*
Y280472D03*
Y360472D03*
Y440472D03*
Y520472D03*
X1565500Y200472D03*
Y280472D03*
Y360472D03*
Y440472D03*
Y520472D03*
G54D31*
X603731Y262614D03*
X605700D03*
X607668D03*
X609637D03*
X611605D03*
X613574D03*
X615542D03*
Y289386D03*
X613574D03*
X611605D03*
X609637D03*
X607668D03*
X605700D03*
X603731D03*
X1146742Y262614D03*
X1148710D03*
X1150679D03*
X1152647D03*
X1154616D03*
X1156584D03*
X1158553D03*
Y289386D03*
X1156584D03*
X1154616D03*
X1152647D03*
X1150679D03*
X1148710D03*
X1146742D03*
G54D13*
X166785Y230000D03*
Y310000D03*
Y390000D03*
Y470000D03*
Y550000D03*
X243785Y230000D03*
Y310000D03*
Y390000D03*
Y470000D03*
Y550000D03*
X1488500Y230000D03*
Y310000D03*
Y390000D03*
Y470000D03*
Y550000D03*
X1565500Y230000D03*
Y310000D03*
Y390000D03*
Y470000D03*
Y550000D03*
G54D40*
X704794Y278000D03*
X1057490Y274000D03*
G54D22*
X561155Y160784D03*
X649200Y254500D03*
X770700Y206900D03*
X776000Y206600D03*
X954200Y200200D03*
X954600Y207200D03*
X1112000Y296000D03*
X1187700Y132400D03*
X1197425Y160284D03*
X1199100Y133300D03*
G54D23*
X601340Y235000D03*
X593860D03*
X664924Y233500D03*
X657444D03*
X720444Y305000D03*
X727924D03*
X1041840Y247000D03*
X1034360D03*
X1074260Y360500D03*
X1096860Y312000D03*
X1104340D03*
X1081740Y360500D03*
X1166860Y312000D03*
X1174340D03*
X1166860Y303000D03*
X1174340D03*
G54D14*
X406600Y169500D03*
Y214000D03*
X412400Y169500D03*
X415200Y180100D03*
X421000D03*
X412400Y214000D03*
X415200Y224500D03*
X421000D03*
X640284Y303500D03*
X646084D03*
X671084Y274000D03*
X665284D03*
X710000Y203000D03*
X704200D03*
X1023200Y203500D03*
X1029000D03*
X1091200Y278000D03*
X1097000D03*
X1122000Y248500D03*
X1116200D03*
X1341200Y160300D03*
Y204400D03*
X1347000Y160300D03*
X1349600Y149500D03*
X1355400D03*
X1347000Y204400D03*
X1349600Y194000D03*
X1355400D03*
G54D50*
X1157740Y337941D03*
Y343059D03*
X1150260D03*
Y340500D03*
Y337941D03*
G54D41*
X706184Y305000D03*
X713184D03*
X1056100Y247000D03*
X1049100D03*
X1629737Y96334D03*
X1636737D03*
G54D32*
X620070Y267142D03*
Y269110D03*
X593298D03*
Y267142D03*
X620070Y271079D03*
Y273047D03*
Y275016D03*
Y276984D03*
Y278953D03*
Y280921D03*
Y282890D03*
Y284858D03*
X593298D03*
Y282890D03*
Y280921D03*
Y278953D03*
Y276984D03*
X1142214Y269110D03*
Y267142D03*
Y284858D03*
Y282890D03*
Y280921D03*
Y278953D03*
Y276984D03*
Y275016D03*
Y273047D03*
Y271079D03*
X1168986Y267142D03*
Y269110D03*
Y271079D03*
Y273047D03*
Y275016D03*
Y282890D03*
Y284858D03*
G54D33*
X606484Y312500D03*
X594884D03*
X623384Y231000D03*
X634984D03*
X695800Y242000D03*
X707400D03*
X1127300Y321000D03*
X1155800Y239500D03*
X1138900Y321000D03*
X1167400Y239500D03*
G54D15*
X417000Y164900D03*
Y159100D03*
X417500Y169600D03*
Y175400D03*
Y208900D03*
Y203100D03*
Y213600D03*
Y219400D03*
X1107000Y355600D03*
Y361400D03*
X1345000Y144900D03*
Y139100D03*
X1344800Y149800D03*
Y155600D03*
X1344500Y188900D03*
Y183100D03*
X1344800Y193700D03*
Y199500D03*
G54D24*
X616666Y239161D03*
Y246839D03*
Y244280D03*
Y241720D03*
X640702Y239161D03*
Y246839D03*
Y244280D03*
Y241720D03*
X1121582Y305161D03*
Y307720D03*
Y310280D03*
Y312839D03*
X1145618Y305161D03*
Y307720D03*
Y310280D03*
Y312839D03*
G54D42*
X739600Y140094D03*
Y176906D03*
X994000Y140094D03*
Y176906D03*
G54D51*
X1170941Y361260D03*
X1176059D03*
Y368740D03*
X1173500D03*
X1170941D03*
G54D16*
X438100Y176084D03*
X612684Y313984D03*
X616684D03*
X635184Y296484D03*
Y304484D03*
X622184Y305484D03*
X1062600Y302484D03*
X1082100D03*
X1074100D03*
X1086100D03*
X1078100D03*
X1090100D03*
X1127100Y274484D03*
X1112500Y361984D03*
X1149600Y249484D03*
X1145600D03*
X1154600Y302484D03*
X1135000Y363984D03*
X1139000D03*
X1176000Y356484D03*
X1170500D03*
X1324100Y156484D03*
X1641077Y130488D03*
G54D52*
X1643500Y147807D03*
Y145248D03*
Y173398D03*
Y170839D03*
Y168280D03*
Y165721D03*
Y163162D03*
Y160603D03*
Y158043D03*
Y155484D03*
Y152925D03*
Y150366D03*
X1666500Y145248D03*
Y147807D03*
Y150366D03*
Y152925D03*
Y155484D03*
Y158043D03*
Y160603D03*
Y163162D03*
Y165721D03*
Y168280D03*
Y170839D03*
Y173398D03*
G54D25*
X594600Y251240D03*
Y243760D03*
X665684Y224240D03*
Y216760D03*
X673684Y224240D03*
Y216760D03*
X681684Y224240D03*
Y216760D03*
X708600Y196740D03*
Y189260D03*
X689684Y224240D03*
Y216760D03*
X690184Y312760D03*
Y320240D03*
X699184Y312760D03*
Y320240D03*
X1024600Y197240D03*
Y189760D03*
X1063100Y239240D03*
Y231760D03*
X1072100Y239240D03*
Y231760D03*
X1072600Y327760D03*
X1064600D03*
X1072600Y335240D03*
X1064600D03*
X1088100Y327760D03*
X1080600D03*
X1088100Y335240D03*
X1080600D03*
X1113000Y353240D03*
Y345760D03*
G54D34*
X635200Y269000D03*
Y264500D03*
Y260000D03*
Y273500D03*
Y288500D03*
X663200Y262500D03*
Y254500D03*
X661200Y267000D03*
X663200Y258500D03*
X664616Y304500D03*
Y300500D03*
X707516Y208000D03*
X688700Y306500D03*
X1024616Y212500D03*
X1061616Y245500D03*
X1066116Y250000D03*
X1067116Y301000D03*
X1094616Y259500D03*
Y255500D03*
Y267500D03*
Y263500D03*
Y243500D03*
Y271500D03*
X1090616Y283000D03*
X1117616Y243500D03*
X1124116Y267500D03*
X1119616Y258500D03*
Y254000D03*
X1120116Y274500D03*
X1131116Y270000D03*
X1154116Y249500D03*
X1154616Y306500D03*
X1162516Y338000D03*
X1627016Y139000D03*
Y149500D03*
X1652516Y138000D03*
X1678016Y141500D03*
Y145500D03*
Y153500D03*
G54D43*
X726100Y195008D03*
Y220992D03*
X752600Y195008D03*
Y220992D03*
X980500Y195008D03*
Y220992D03*
X1007000Y195008D03*
Y220992D03*
G54D26*
X607668Y245500D03*
X608168Y302500D03*
X642168Y277500D03*
X631168Y282000D03*
X638168Y284500D03*
X642668Y298000D03*
Y293500D03*
X644584Y308500D03*
X671668Y269000D03*
X667668Y292500D03*
Y296500D03*
Y280500D03*
Y284500D03*
Y288500D03*
X667584Y308500D03*
X710484Y212000D03*
X695168Y251000D03*
X700668Y306500D03*
X696168Y302000D03*
X1027584Y208500D03*
X1073584Y245500D03*
X1097584Y247500D03*
Y251500D03*
X1099084Y297500D03*
Y289500D03*
X1101084Y285000D03*
X1099084Y293500D03*
X1127084Y263500D03*
Y278500D03*
Y283000D03*
Y287500D03*
Y292000D03*
X1629984Y146000D03*
Y142500D03*
Y153500D03*
X1664084Y138000D03*
X1680984Y149500D03*
X1738984Y181000D03*
Y186500D03*
X1769984Y184000D03*
G54D17*
X438100Y173117D03*
X612684Y311017D03*
X616684D03*
X635184Y293517D03*
Y301517D03*
X622184Y302517D03*
X1062600Y299517D03*
X1082100D03*
X1074100D03*
X1086100D03*
X1078100D03*
X1090100D03*
X1127100Y271517D03*
X1112500Y359017D03*
X1149600Y246517D03*
X1145600D03*
X1154600Y299517D03*
X1135000Y361017D03*
X1139000D03*
X1176000Y353517D03*
X1170500D03*
X1324100Y153517D03*
X1641077Y127521D03*
G54D44*
X729184Y285800D03*
Y274200D03*
X1033100Y266200D03*
Y277800D03*
X1055100Y301200D03*
Y312800D03*
G54D35*
X638167Y269000D03*
Y264500D03*
Y260000D03*
Y273500D03*
Y288500D03*
X666167Y262500D03*
Y254500D03*
X664167Y267000D03*
X666167Y258500D03*
X667583Y304500D03*
Y300500D03*
X710483Y208000D03*
X691667Y306500D03*
X1027583Y212500D03*
X1064583Y245500D03*
X1069083Y250000D03*
X1070083Y301000D03*
X1097583Y259500D03*
Y255500D03*
Y267500D03*
Y263500D03*
Y243500D03*
Y271500D03*
X1093583Y283000D03*
X1120583Y243500D03*
X1127083Y267500D03*
X1122583Y258500D03*
Y254000D03*
X1123083Y274500D03*
X1134083Y270000D03*
X1157083Y249500D03*
X1157583Y306500D03*
X1165483Y338000D03*
X1629983Y139000D03*
Y149500D03*
X1655483Y138000D03*
X1680983Y141500D03*
Y145500D03*
Y153500D03*
G54D53*
X1846142Y230433D03*
Y240433D03*
X1856772D03*
Y230433D03*
X1846142Y250433D03*
Y260433D03*
Y270433D03*
X1856772D03*
Y260433D03*
Y250433D03*
X1846142Y280433D03*
Y290433D03*
Y300433D03*
X1856772D03*
Y290433D03*
Y280433D03*
X1848957Y324213D03*
X1843957Y329213D03*
X1848957Y314213D03*
X1843957Y319213D03*
X1853957Y329213D03*
Y319213D03*
X1858957Y324213D03*
Y314213D03*
X1848957Y334213D03*
Y344213D03*
X1843957Y339213D03*
Y349213D03*
X1853957D03*
Y339213D03*
X1858957Y344213D03*
Y334213D03*
G54D54*
G01X-457143Y-1211429D02*
Y2242857D01*
X4308572D01*
Y-1211429D01*
X-457143D01*
G01X37000Y-995000D02*
Y-1070000D01*
X537000D01*
Y-995000D01*
X37000D01*
G01X49000Y-1060000D02*
Y-1065000D01*
G01X47543Y-1060000D02*
X50457D01*
G01X55367Y-1065000D02*
X52833D01*
Y-1060000D01*
X55367D01*
G01X54353Y-1062417D02*
X52833D01*
G01X57933Y-1060000D02*
Y-1065000D01*
X60467D01*
G01X64300Y-1065167D02*
X64173Y-1065083D01*
Y-1064917D01*
X64300Y-1064833D01*
X64427Y-1064917D01*
Y-1065083D01*
X64300Y-1065167D01*
G01Y-1062917D02*
X64173Y-1062833D01*
Y-1062667D01*
X64300Y-1062583D01*
X64427Y-1062667D01*
Y-1062833D01*
X64300Y-1062917D01*
G01X69083Y-1066667D02*
X68450Y-1065833D01*
X68133Y-1065000D01*
Y-1061667D01*
X68450Y-1060833D01*
X69083Y-1060000D01*
G01X74500D02*
X73993Y-1060167D01*
X73613Y-1060583D01*
X73360Y-1061083D01*
X73170Y-1061750D01*
X73107Y-1062500D01*
X73170Y-1063250D01*
X73360Y-1063917D01*
X73613Y-1064417D01*
X73993Y-1064833D01*
X74500Y-1065000D01*
X75007Y-1064833D01*
X75387Y-1064417D01*
X75640Y-1063917D01*
X75830Y-1063250D01*
X75893Y-1062500D01*
X75830Y-1061750D01*
X75640Y-1061083D01*
X75387Y-1060583D01*
X75007Y-1060167D01*
X74500Y-1060000D01*
G01X78207Y-1064000D02*
X78587Y-1064583D01*
X79093Y-1064917D01*
X79663Y-1065000D01*
X80170Y-1064917D01*
X80677Y-1064500D01*
X80993Y-1064000D01*
X81057Y-1063500D01*
X80930Y-1062917D01*
X80487Y-1062500D01*
X80043Y-1062333D01*
X79473D01*
G01X80043D02*
X80423Y-1062083D01*
X80740Y-1061667D01*
X80867Y-1061167D01*
X80740Y-1060667D01*
X80423Y-1060250D01*
X79853Y-1060000D01*
X79283Y-1060083D01*
X78713Y-1060417D01*
G01X85017Y-1066667D02*
X85650Y-1065833D01*
X85967Y-1065000D01*
Y-1061667D01*
X85650Y-1060833D01*
X85017Y-1060000D01*
G01X88407Y-1064000D02*
X88787Y-1064583D01*
X89293Y-1064917D01*
X89863Y-1065000D01*
X90370Y-1064917D01*
X90877Y-1064500D01*
X91193Y-1064000D01*
X91257Y-1063500D01*
X91130Y-1062917D01*
X90687Y-1062500D01*
X90243Y-1062333D01*
X89673D01*
G01X90243D02*
X90623Y-1062083D01*
X90940Y-1061667D01*
X91067Y-1061167D01*
X90940Y-1060667D01*
X90623Y-1060250D01*
X90053Y-1060000D01*
X89483Y-1060083D01*
X88913Y-1060417D01*
G01X93697Y-1060833D02*
X94077Y-1060333D01*
X94520Y-1060083D01*
X95027Y-1060000D01*
X95660Y-1060167D01*
X96103Y-1060583D01*
X96230Y-1061083D01*
X96167Y-1061583D01*
X95913Y-1062000D01*
X94647Y-1062833D01*
X94077Y-1063417D01*
X93697Y-1064250D01*
X93570Y-1065000D01*
X96230D01*
G01X99873D02*
X100000Y-1063917D01*
X100190Y-1063000D01*
X100443Y-1062167D01*
X100760Y-1061250D01*
X101267Y-1060000D01*
X98733D01*
G01X104277Y-1063333D02*
X105923D01*
G01X108997Y-1060833D02*
X109377Y-1060333D01*
X109820Y-1060083D01*
X110327Y-1060000D01*
X110960Y-1060167D01*
X111403Y-1060583D01*
X111530Y-1061083D01*
X111467Y-1061583D01*
X111213Y-1062000D01*
X109947Y-1062833D01*
X109377Y-1063417D01*
X108997Y-1064250D01*
X108870Y-1065000D01*
X111530D01*
G01X113907Y-1064000D02*
X114287Y-1064583D01*
X114793Y-1064917D01*
X115363Y-1065000D01*
X115870Y-1064917D01*
X116377Y-1064500D01*
X116693Y-1064000D01*
X116757Y-1063500D01*
X116630Y-1062917D01*
X116187Y-1062500D01*
X115743Y-1062333D01*
X115173D01*
G01X115743D02*
X116123Y-1062083D01*
X116440Y-1061667D01*
X116567Y-1061167D01*
X116440Y-1060667D01*
X116123Y-1060250D01*
X115553Y-1060000D01*
X114983Y-1060083D01*
X114413Y-1060417D01*
G01X121160Y-1065000D02*
Y-1060000D01*
X118817Y-1063583D01*
X121983D01*
G01X124107Y-1064250D02*
X124487Y-1064667D01*
X124930Y-1064917D01*
X125500Y-1065000D01*
X126070Y-1064833D01*
X126513Y-1064500D01*
X126830Y-1063917D01*
X126893Y-1063250D01*
X126767Y-1062583D01*
X126450Y-1062167D01*
X126007Y-1061833D01*
X125563Y-1061750D01*
X125120Y-1061833D01*
X124550Y-1062167D01*
X124740Y-1060000D01*
X126450D01*
G01X134497Y-1065000D02*
Y-1060000D01*
X136903D01*
G01X136017Y-1062417D02*
X134497D01*
G01X139217Y-1065000D02*
X140800Y-1060000D01*
X142383Y-1065000D01*
G01X141813Y-1063250D02*
X139787D01*
G01X144570Y-1065000D02*
X147230Y-1060000D01*
G01X144570D02*
X147230Y-1065000D01*
G01X151000Y-1065167D02*
X150873Y-1065083D01*
Y-1064917D01*
X151000Y-1064833D01*
X151127Y-1064917D01*
Y-1065083D01*
X151000Y-1065167D01*
G01Y-1062917D02*
X150873Y-1062833D01*
Y-1062667D01*
X151000Y-1062583D01*
X151127Y-1062667D01*
Y-1062833D01*
X151000Y-1062917D01*
G01X155783Y-1066667D02*
X155150Y-1065833D01*
X154833Y-1065000D01*
Y-1061667D01*
X155150Y-1060833D01*
X155783Y-1060000D01*
G01X161200D02*
X160693Y-1060167D01*
X160313Y-1060583D01*
X160060Y-1061083D01*
X159870Y-1061750D01*
X159807Y-1062500D01*
X159870Y-1063250D01*
X160060Y-1063917D01*
X160313Y-1064417D01*
X160693Y-1064833D01*
X161200Y-1065000D01*
X161707Y-1064833D01*
X162087Y-1064417D01*
X162340Y-1063917D01*
X162530Y-1063250D01*
X162593Y-1062500D01*
X162530Y-1061750D01*
X162340Y-1061083D01*
X162087Y-1060583D01*
X161707Y-1060167D01*
X161200Y-1060000D01*
G01X164907Y-1064000D02*
X165287Y-1064583D01*
X165793Y-1064917D01*
X166363Y-1065000D01*
X166870Y-1064917D01*
X167377Y-1064500D01*
X167693Y-1064000D01*
X167757Y-1063500D01*
X167630Y-1062917D01*
X167187Y-1062500D01*
X166743Y-1062333D01*
X166173D01*
G01X166743D02*
X167123Y-1062083D01*
X167440Y-1061667D01*
X167567Y-1061167D01*
X167440Y-1060667D01*
X167123Y-1060250D01*
X166553Y-1060000D01*
X165983Y-1060083D01*
X165413Y-1060417D01*
G01X171717Y-1066667D02*
X172350Y-1065833D01*
X172667Y-1065000D01*
Y-1061667D01*
X172350Y-1060833D01*
X171717Y-1060000D01*
G01X175107Y-1064000D02*
X175487Y-1064583D01*
X175993Y-1064917D01*
X176563Y-1065000D01*
X177070Y-1064917D01*
X177577Y-1064500D01*
X177893Y-1064000D01*
X177957Y-1063500D01*
X177830Y-1062917D01*
X177387Y-1062500D01*
X176943Y-1062333D01*
X176373D01*
G01X176943D02*
X177323Y-1062083D01*
X177640Y-1061667D01*
X177767Y-1061167D01*
X177640Y-1060667D01*
X177323Y-1060250D01*
X176753Y-1060000D01*
X176183Y-1060083D01*
X175613Y-1060417D01*
G01X180523Y-1064417D02*
X180967Y-1064833D01*
X181473Y-1065000D01*
X181980Y-1064833D01*
X182423Y-1064333D01*
X182740Y-1063583D01*
X182867Y-1062833D01*
Y-1061917D01*
X182740Y-1061167D01*
X182423Y-1060500D01*
X182043Y-1060167D01*
X181600Y-1060000D01*
X181093Y-1060167D01*
X180713Y-1060500D01*
X180460Y-1061000D01*
X180333Y-1061667D01*
X180460Y-1062250D01*
X180777Y-1062833D01*
X181157Y-1063167D01*
X181600Y-1063250D01*
X182107Y-1063083D01*
X182487Y-1062667D01*
X182867Y-1061917D01*
G01X186573Y-1065000D02*
X186700Y-1063917D01*
X186890Y-1063000D01*
X187143Y-1062167D01*
X187460Y-1061250D01*
X187967Y-1060000D01*
X185433D01*
G01X190977Y-1063333D02*
X192623D01*
G01X195507Y-1064000D02*
X195887Y-1064583D01*
X196393Y-1064917D01*
X196963Y-1065000D01*
X197470Y-1064917D01*
X197977Y-1064500D01*
X198293Y-1064000D01*
X198357Y-1063500D01*
X198230Y-1062917D01*
X197787Y-1062500D01*
X197343Y-1062333D01*
X196773D01*
G01X197343D02*
X197723Y-1062083D01*
X198040Y-1061667D01*
X198167Y-1061167D01*
X198040Y-1060667D01*
X197723Y-1060250D01*
X197153Y-1060000D01*
X196583Y-1060083D01*
X196013Y-1060417D01*
G01X200797Y-1062917D02*
X201240Y-1062333D01*
X201620Y-1062000D01*
X202127Y-1061833D01*
X202570Y-1062000D01*
X202887Y-1062333D01*
X203140Y-1062833D01*
X203203Y-1063417D01*
X203140Y-1063917D01*
X202887Y-1064417D01*
X202507Y-1064833D01*
X202063Y-1065000D01*
X201557Y-1064833D01*
X201113Y-1064333D01*
X200860Y-1063583D01*
X200797Y-1062750D01*
X200923Y-1061667D01*
X201113Y-1061083D01*
X201430Y-1060500D01*
X201873Y-1060083D01*
X202317Y-1060000D01*
X202760Y-1060167D01*
X203077Y-1060583D01*
G01X207100Y-1065000D02*
Y-1060000D01*
X206340Y-1061000D01*
G01Y-1065000D02*
X207860D01*
G01X212960D02*
Y-1060000D01*
X210617Y-1063583D01*
X213783D01*
G01X232000Y-995000D02*
Y-1070000D01*
G01Y-1045000D02*
X335000D01*
Y-1020000D01*
G01X232000D02*
X335000D01*
G01X337000Y-995000D02*
Y-1070000D01*
G01X335000Y-995000D02*
Y-1070000D01*
G01X342507Y-1055000D02*
Y-1050000D01*
X343773D01*
X344280Y-1050250D01*
X344660Y-1050583D01*
X344977Y-1051083D01*
X345230Y-1051667D01*
X345293Y-1052500D01*
X345230Y-1053333D01*
X344977Y-1053917D01*
X344660Y-1054417D01*
X344280Y-1054750D01*
X343773Y-1055000D01*
X342507D01*
G01X347417D02*
X349000Y-1050000D01*
X350583Y-1055000D01*
G01X350013Y-1053250D02*
X347987D01*
G01X354100Y-1050000D02*
Y-1055000D01*
G01X352643Y-1050000D02*
X355557D01*
G01X360467Y-1055000D02*
X357933D01*
Y-1050000D01*
X360467D01*
G01X359453Y-1052417D02*
X357933D01*
G01X364300Y-1055167D02*
X364173Y-1055083D01*
Y-1054917D01*
X364300Y-1054833D01*
X364427Y-1054917D01*
Y-1055083D01*
X364300Y-1055167D01*
G01Y-1052917D02*
X364173Y-1052833D01*
Y-1052667D01*
X364300Y-1052583D01*
X364427Y-1052667D01*
Y-1052833D01*
X364300Y-1052917D01*
G01X337000Y-1045000D02*
X537000D01*
G01X342633Y-1030000D02*
Y-1025000D01*
X344153D01*
X344660Y-1025250D01*
X345040Y-1025833D01*
X345167Y-1026500D01*
X345040Y-1027167D01*
X344723Y-1027667D01*
X344153Y-1027917D01*
X342633D01*
G01X347860Y-1030167D02*
X350140Y-1025000D01*
G01X352643Y-1030000D02*
Y-1025000D01*
X355557Y-1030000D01*
Y-1025000D01*
G01X359200Y-1030167D02*
X359073Y-1030083D01*
Y-1029917D01*
X359200Y-1029833D01*
X359327Y-1029917D01*
Y-1030083D01*
X359200Y-1030167D01*
G01Y-1027917D02*
X359073Y-1027833D01*
Y-1027667D01*
X359200Y-1027583D01*
X359327Y-1027667D01*
Y-1027833D01*
X359200Y-1027917D01*
G01X342633Y-1005000D02*
Y-1000000D01*
X344153D01*
X344660Y-1000250D01*
X345040Y-1000833D01*
X345167Y-1001500D01*
X345040Y-1002167D01*
X344723Y-1002667D01*
X344153Y-1002917D01*
X342633D01*
G01X347733Y-1005000D02*
Y-1000000D01*
X349317D01*
X349823Y-1000250D01*
X350140Y-1000583D01*
X350267Y-1001250D01*
X350140Y-1001917D01*
X349760Y-1002333D01*
X349317Y-1002583D01*
X347733D01*
G01X349317D02*
X350267Y-1005000D01*
G01X354100D02*
X353593Y-1004917D01*
X353150Y-1004583D01*
X352770Y-1004083D01*
X352517Y-1003500D01*
X352390Y-1002833D01*
Y-1002167D01*
X352517Y-1001500D01*
X352770Y-1000917D01*
X353150Y-1000417D01*
X353593Y-1000083D01*
X354100Y-1000000D01*
X354607Y-1000083D01*
X355050Y-1000417D01*
X355430Y-1000917D01*
X355683Y-1001500D01*
X355810Y-1002167D01*
Y-1002833D01*
X355683Y-1003500D01*
X355430Y-1004083D01*
X355050Y-1004583D01*
X354607Y-1004917D01*
X354100Y-1005000D01*
G01X357933Y-1004000D02*
X358250Y-1004500D01*
X358630Y-1004833D01*
X359073Y-1005000D01*
X359580Y-1004833D01*
X359960Y-1004500D01*
X360340Y-1004000D01*
X360467Y-1003333D01*
Y-1000000D01*
G01X365567Y-1005000D02*
X363033D01*
Y-1000000D01*
X365567D01*
G01X364553Y-1002417D02*
X363033D01*
G01X370793Y-1000417D02*
X370413Y-1000167D01*
X369970Y-1000000D01*
X369463D01*
X368893Y-1000250D01*
X368450Y-1000667D01*
X368133Y-1001167D01*
X367880Y-1002000D01*
X367817Y-1002750D01*
X367943Y-1003500D01*
X368133Y-1004000D01*
X368513Y-1004500D01*
X368957Y-1004833D01*
X369400Y-1005000D01*
X369843D01*
X370287Y-1004833D01*
X370667Y-1004583D01*
X370983Y-1004250D01*
G01X374500Y-1000000D02*
Y-1005000D01*
G01X373043Y-1000000D02*
X375957D01*
G01X379600Y-1005167D02*
X379473Y-1005083D01*
Y-1004917D01*
X379600Y-1004833D01*
X379727Y-1004917D01*
Y-1005083D01*
X379600Y-1005167D01*
G01Y-1002917D02*
X379473Y-1002833D01*
Y-1002667D01*
X379600Y-1002583D01*
X379727Y-1002667D01*
Y-1002833D01*
X379600Y-1002917D01*
G01X337000Y-1020000D02*
X537000D01*
G01X452000Y-1045000D02*
Y-1070000D01*
G01X454633Y-1047500D02*
Y-1052500D01*
X457167D01*
G01X460240Y-1047500D02*
X461760D01*
G01X461000D02*
Y-1052500D01*
G01X460240D02*
X461760D01*
G01X466607Y-1049833D02*
X466860Y-1049583D01*
X467050Y-1049167D01*
X467177Y-1048583D01*
X467050Y-1048083D01*
X466797Y-1047750D01*
X466353Y-1047500D01*
X464643D01*
Y-1052500D01*
X466733D01*
X467177Y-1052167D01*
X467430Y-1051667D01*
X467557Y-1051083D01*
X467430Y-1050500D01*
X467050Y-1050000D01*
X466607Y-1049833D01*
X464643D01*
G01X471200Y-1052667D02*
X471073Y-1052583D01*
Y-1052417D01*
X471200Y-1052333D01*
X471327Y-1052417D01*
Y-1052583D01*
X471200Y-1052667D01*
G01Y-1050417D02*
X471073Y-1050333D01*
Y-1050167D01*
X471200Y-1050083D01*
X471327Y-1050167D01*
Y-1050333D01*
X471200Y-1050417D01*
G01X495000Y-1045000D02*
Y-1070000D01*
G01X498900Y-1047500D02*
Y-1052500D01*
G01X497443Y-1047500D02*
X500357D01*
G01X504000Y-1052500D02*
X503620Y-1052417D01*
X503240Y-1052083D01*
X502987Y-1051500D01*
X502860Y-1050833D01*
X502987Y-1050167D01*
X503240Y-1049583D01*
X503620Y-1049250D01*
X504000Y-1049167D01*
X504380Y-1049250D01*
X504760Y-1049583D01*
X505013Y-1050167D01*
X505077Y-1050833D01*
X505013Y-1051500D01*
X504760Y-1052083D01*
X504380Y-1052417D01*
X504000Y-1052500D01*
G01X509100D02*
X508720Y-1052417D01*
X508340Y-1052083D01*
X508087Y-1051500D01*
X507960Y-1050833D01*
X508087Y-1050167D01*
X508340Y-1049583D01*
X508720Y-1049250D01*
X509100Y-1049167D01*
X509480Y-1049250D01*
X509860Y-1049583D01*
X510113Y-1050167D01*
X510177Y-1050833D01*
X510113Y-1051500D01*
X509860Y-1052083D01*
X509480Y-1052417D01*
X509100Y-1052500D01*
G01X514200D02*
Y-1047500D01*
G01X519300Y-1052667D02*
X519173Y-1052583D01*
Y-1052417D01*
X519300Y-1052333D01*
X519427Y-1052417D01*
Y-1052583D01*
X519300Y-1052667D01*
G01Y-1050417D02*
X519173Y-1050333D01*
Y-1050167D01*
X519300Y-1050083D01*
X519427Y-1050167D01*
Y-1050333D01*
X519300Y-1050417D01*
G01X495000Y-1020000D02*
Y-1045000D01*
G01X497633Y-1027500D02*
Y-1022500D01*
X499217D01*
X499723Y-1022750D01*
X500040Y-1023083D01*
X500167Y-1023750D01*
X500040Y-1024417D01*
X499660Y-1024833D01*
X499217Y-1025083D01*
X497633D01*
G01X499217D02*
X500167Y-1027500D01*
G01X505267D02*
X502733D01*
Y-1022500D01*
X505267D01*
G01X504253Y-1024917D02*
X502733D01*
G01X507517Y-1022500D02*
X509100Y-1027500D01*
X510683Y-1022500D01*
G01X514200Y-1027667D02*
X514073Y-1027583D01*
Y-1027417D01*
X514200Y-1027333D01*
X514327Y-1027417D01*
Y-1027583D01*
X514200Y-1027667D01*
G01Y-1025417D02*
X514073Y-1025333D01*
Y-1025167D01*
X514200Y-1025083D01*
X514327Y-1025167D01*
Y-1025333D01*
X514200Y-1025417D01*
G01X503013Y-1073167D02*
X503120Y-1073042D01*
X503200Y-1072833D01*
X503253Y-1072542D01*
X503200Y-1072292D01*
X503093Y-1072125D01*
X502907Y-1072000D01*
X502187D01*
Y-1074500D01*
X503067D01*
X503253Y-1074333D01*
X503360Y-1074083D01*
X503413Y-1073792D01*
X503360Y-1073500D01*
X503200Y-1073250D01*
X503013Y-1073167D01*
X502187D01*
G01X505480Y-1074500D02*
Y-1072833D01*
G01Y-1073125D02*
X505373Y-1072958D01*
X505213Y-1072875D01*
X505027Y-1072833D01*
X504840Y-1072917D01*
X504680Y-1073083D01*
X504573Y-1073333D01*
X504520Y-1073667D01*
X504573Y-1074000D01*
X504680Y-1074250D01*
X504840Y-1074417D01*
X505027Y-1074500D01*
X505213Y-1074458D01*
X505373Y-1074333D01*
X505480Y-1074167D01*
G01X506800Y-1074208D02*
X506933Y-1074375D01*
X507120Y-1074500D01*
X507280D01*
X507440Y-1074417D01*
X507547Y-1074292D01*
X507600Y-1074125D01*
X507573Y-1073875D01*
X507467Y-1073750D01*
X506987Y-1073500D01*
X506880Y-1073208D01*
X506933Y-1073000D01*
X507040Y-1072875D01*
X507200Y-1072833D01*
X507360Y-1072875D01*
X507520Y-1073000D01*
G01X509000Y-1073375D02*
X509853D01*
X509773Y-1073083D01*
X509640Y-1072917D01*
X509453Y-1072833D01*
X509267Y-1072875D01*
X509107Y-1073000D01*
X509000Y-1073292D01*
X508947Y-1073542D01*
Y-1073792D01*
X509000Y-1074042D01*
X509133Y-1074292D01*
X509293Y-1074458D01*
X509480Y-1074500D01*
X509667Y-1074417D01*
X509853Y-1074167D01*
G01X511120Y-1074500D02*
Y-1072000D01*
G01Y-1073250D02*
X511253Y-1073000D01*
X511413Y-1072875D01*
X511573Y-1072833D01*
X511813Y-1072917D01*
X511973Y-1073083D01*
X512080Y-1073375D01*
Y-1073708D01*
X512027Y-1074042D01*
X511920Y-1074292D01*
X511733Y-1074458D01*
X511573Y-1074500D01*
X511413Y-1074458D01*
X511253Y-1074333D01*
X511120Y-1074125D01*
G01X513800Y-1074500D02*
X513640Y-1074458D01*
X513480Y-1074292D01*
X513373Y-1074000D01*
X513320Y-1073667D01*
X513373Y-1073333D01*
X513480Y-1073042D01*
X513640Y-1072875D01*
X513800Y-1072833D01*
X513960Y-1072875D01*
X514120Y-1073042D01*
X514227Y-1073333D01*
X514253Y-1073667D01*
X514227Y-1074000D01*
X514120Y-1074292D01*
X513960Y-1074458D01*
X513800Y-1074500D01*
G01X516480D02*
Y-1072833D01*
G01Y-1073125D02*
X516373Y-1072958D01*
X516213Y-1072875D01*
X516027Y-1072833D01*
X515840Y-1072917D01*
X515680Y-1073083D01*
X515573Y-1073333D01*
X515520Y-1073667D01*
X515573Y-1074000D01*
X515680Y-1074250D01*
X515840Y-1074417D01*
X516027Y-1074500D01*
X516213Y-1074458D01*
X516373Y-1074333D01*
X516480Y-1074167D01*
G01X517827Y-1074500D02*
Y-1072833D01*
G01Y-1073167D02*
X517960Y-1073000D01*
X518093Y-1072875D01*
X518280Y-1072833D01*
X518413Y-1072875D01*
X518573Y-1073000D01*
G01X520880Y-1072000D02*
Y-1074500D01*
G01Y-1074125D02*
X520773Y-1074333D01*
X520613Y-1074458D01*
X520427Y-1074500D01*
X520213Y-1074417D01*
X520053Y-1074208D01*
X519947Y-1073958D01*
X519920Y-1073667D01*
X519947Y-1073375D01*
X520053Y-1073125D01*
X520213Y-1072917D01*
X520427Y-1072833D01*
X520613Y-1072875D01*
X520747Y-1072958D01*
X520880Y-1073125D01*
G01X524267Y-1074500D02*
Y-1072000D01*
X524933D01*
X525147Y-1072125D01*
X525280Y-1072292D01*
X525333Y-1072625D01*
X525280Y-1072958D01*
X525120Y-1073167D01*
X524933Y-1073292D01*
X524267D01*
G01X524933D02*
X525333Y-1074500D01*
G01X526600Y-1073375D02*
X527453D01*
X527373Y-1073083D01*
X527240Y-1072917D01*
X527053Y-1072833D01*
X526867Y-1072875D01*
X526707Y-1073000D01*
X526600Y-1073292D01*
X526547Y-1073542D01*
Y-1073792D01*
X526600Y-1074042D01*
X526733Y-1074292D01*
X526893Y-1074458D01*
X527080Y-1074500D01*
X527267Y-1074417D01*
X527453Y-1074167D01*
G01X528720Y-1072833D02*
X529200Y-1074500D01*
X529680Y-1072833D01*
G01X531400Y-1074583D02*
X531347Y-1074542D01*
Y-1074458D01*
X531400Y-1074417D01*
X531453Y-1074458D01*
Y-1074542D01*
X531400Y-1074583D01*
G01X533600Y-1074500D02*
X533787Y-1074458D01*
X534000Y-1074333D01*
X534133Y-1074125D01*
X534187Y-1073833D01*
X534133Y-1073542D01*
X533973Y-1073292D01*
X533733Y-1073167D01*
X533467D01*
X533307Y-1073083D01*
X533173Y-1072875D01*
X533120Y-1072583D01*
X533200Y-1072292D01*
X533387Y-1072083D01*
X533600Y-1072000D01*
X533813Y-1072083D01*
X534000Y-1072292D01*
X534080Y-1072583D01*
X534027Y-1072875D01*
X533893Y-1073083D01*
X533733Y-1073167D01*
X533467D01*
X533227Y-1073292D01*
X533067Y-1073542D01*
X533013Y-1073833D01*
X533067Y-1074125D01*
X533200Y-1074333D01*
X533413Y-1074458D01*
X533600Y-1074500D01*
G01X536013Y-1073167D02*
X536120Y-1073042D01*
X536200Y-1072833D01*
X536253Y-1072542D01*
X536200Y-1072292D01*
X536093Y-1072125D01*
X535907Y-1072000D01*
X535187D01*
Y-1074500D01*
X536067D01*
X536253Y-1074333D01*
X536360Y-1074083D01*
X536413Y-1073792D01*
X536360Y-1073500D01*
X536200Y-1073250D01*
X536013Y-1073167D01*
X535187D01*
G01X-457143Y-1211429D02*
Y2242857D01*
X4308572D01*
Y-1211429D01*
X-457143D01*
G01X71650Y-1024800D02*
X69130Y-1024383D01*
X66925Y-1022717D01*
X65035Y-1020217D01*
X63775Y-1017300D01*
X63145Y-1013967D01*
Y-1010633D01*
X63775Y-1007300D01*
X65035Y-1004383D01*
X66925Y-1001884D01*
X69130Y-1000217D01*
X71650Y-999800D01*
X74170Y-1000217D01*
X76375Y-1001884D01*
X78265Y-1004383D01*
X79525Y-1007300D01*
X80155Y-1010633D01*
Y-1013967D01*
X79525Y-1017300D01*
X78265Y-1020217D01*
X76375Y-1022717D01*
X74170Y-1024383D01*
X71650Y-1024800D01*
G01X74170Y-1018133D02*
X77950Y-1024800D01*
G01X91495Y-1008134D02*
Y-1019800D01*
X92755Y-1022717D01*
X94645Y-1024383D01*
X96850Y-1024800D01*
X99055Y-1024383D01*
X100945Y-1022717D01*
X102205Y-1019800D01*
G01Y-1024800D02*
Y-1008134D01*
G01X127720Y-1024800D02*
Y-1008134D01*
G01Y-1011050D02*
X126460Y-1009384D01*
X124570Y-1008550D01*
X122365Y-1008134D01*
X120160Y-1008967D01*
X118270Y-1010633D01*
X117010Y-1013134D01*
X116380Y-1016467D01*
X117010Y-1019800D01*
X118270Y-1022301D01*
X120160Y-1023967D01*
X122365Y-1024800D01*
X124570Y-1024383D01*
X126460Y-1023134D01*
X127720Y-1021467D01*
G01X141895Y-1024800D02*
Y-1008134D01*
G01Y-1012300D02*
X143155Y-1010217D01*
X145045Y-1008550D01*
X147565Y-1008134D01*
X149770Y-1008550D01*
X151660Y-1010217D01*
X152605Y-1013134D01*
Y-1024800D01*
G01X172450Y-999800D02*
Y-1024800D01*
G01X168040Y-1008134D02*
X176860D01*
G01X203320Y-1024800D02*
Y-1008134D01*
G01Y-1011050D02*
X202060Y-1009384D01*
X200170Y-1008550D01*
X197965Y-1008134D01*
X195760Y-1008967D01*
X193870Y-1010633D01*
X192610Y-1013134D01*
X191980Y-1016467D01*
X192610Y-1019800D01*
X193870Y-1022301D01*
X195760Y-1023967D01*
X197965Y-1024800D01*
X200170Y-1024383D01*
X202060Y-1023134D01*
X203320Y-1021467D01*
G01X49820Y-1042350D02*
X51387D01*
Y-1044240D01*
X50917Y-1044870D01*
X50368Y-1045290D01*
X49585Y-1045500D01*
X48802Y-1045290D01*
X48253Y-1044870D01*
X47783Y-1044240D01*
X47470Y-1043505D01*
X47313Y-1042665D01*
Y-1041930D01*
X47470Y-1041300D01*
X47783Y-1040565D01*
X48253Y-1039935D01*
X48723Y-1039515D01*
X49350Y-1039200D01*
X49898D01*
X50525Y-1039410D01*
X50995Y-1039830D01*
G01X53927Y-1039200D02*
Y-1043715D01*
X54240Y-1044660D01*
X54867Y-1045290D01*
X55650Y-1045500D01*
X56433Y-1045290D01*
X57060Y-1044660D01*
X57373Y-1043715D01*
Y-1039200D01*
G01X61010D02*
X62890D01*
G01X61950D02*
Y-1045500D01*
G01X61010D02*
X62890D01*
G01X66605Y-1044660D02*
X67232Y-1045185D01*
X67937Y-1045500D01*
X68563D01*
X69190Y-1045185D01*
X69660Y-1044660D01*
X69895Y-1043925D01*
X69738Y-1043190D01*
X69347Y-1042560D01*
X68642Y-1042140D01*
X67702Y-1041930D01*
X67153Y-1041510D01*
X66918Y-1040775D01*
X67075Y-1040040D01*
X67467Y-1039515D01*
X68015Y-1039200D01*
X68563D01*
X69112Y-1039410D01*
X69582Y-1039935D01*
G01X72905Y-1045500D02*
Y-1039200D01*
G01X76195D02*
Y-1045500D01*
G01Y-1042350D02*
X72905D01*
G01X78892Y-1045500D02*
X80850Y-1039200D01*
X82808Y-1045500D01*
G01X82103Y-1043295D02*
X79597D01*
G01X85348Y-1045500D02*
Y-1039200D01*
X88952Y-1045500D01*
Y-1039200D01*
G01X98027Y-1045500D02*
Y-1039200D01*
X99593D01*
X100220Y-1039515D01*
X100690Y-1039935D01*
X101082Y-1040565D01*
X101395Y-1041300D01*
X101473Y-1042350D01*
X101395Y-1043400D01*
X101082Y-1044135D01*
X100690Y-1044765D01*
X100220Y-1045185D01*
X99593Y-1045500D01*
X98027D01*
G01X105110Y-1039200D02*
X106990D01*
G01X106050D02*
Y-1045500D01*
G01X105110D02*
X106990D01*
G01X110705Y-1044660D02*
X111332Y-1045185D01*
X112037Y-1045500D01*
X112663D01*
X113290Y-1045185D01*
X113760Y-1044660D01*
X113995Y-1043925D01*
X113838Y-1043190D01*
X113447Y-1042560D01*
X112742Y-1042140D01*
X111802Y-1041930D01*
X111253Y-1041510D01*
X111018Y-1040775D01*
X111175Y-1040040D01*
X111567Y-1039515D01*
X112115Y-1039200D01*
X112663D01*
X113212Y-1039410D01*
X113682Y-1039935D01*
G01X118650Y-1039200D02*
Y-1045500D01*
G01X116848Y-1039200D02*
X120452D01*
G01X124950Y-1045710D02*
X124793Y-1045605D01*
Y-1045395D01*
X124950Y-1045290D01*
X125107Y-1045395D01*
Y-1045605D01*
X124950Y-1045710D01*
G01X131093Y-1046655D02*
X131407Y-1045290D01*
G01X137550Y-1039200D02*
Y-1045500D01*
G01X135748Y-1039200D02*
X139352D01*
G01X141892Y-1045500D02*
X143850Y-1039200D01*
X145808Y-1045500D01*
G01X145103Y-1043295D02*
X142597D01*
G01X150150Y-1045500D02*
X149523Y-1045395D01*
X148975Y-1044975D01*
X148505Y-1044345D01*
X148192Y-1043610D01*
X148035Y-1042770D01*
Y-1041930D01*
X148192Y-1041090D01*
X148505Y-1040355D01*
X148975Y-1039725D01*
X149523Y-1039305D01*
X150150Y-1039200D01*
X150777Y-1039305D01*
X151325Y-1039725D01*
X151795Y-1040355D01*
X152108Y-1041090D01*
X152265Y-1041930D01*
Y-1042770D01*
X152108Y-1043610D01*
X151795Y-1044345D01*
X151325Y-1044975D01*
X150777Y-1045395D01*
X150150Y-1045500D01*
G01X156450D02*
Y-1042665D01*
X154883Y-1039200D01*
G01X158017D02*
X156450Y-1042665D01*
G01X161027Y-1039200D02*
Y-1043715D01*
X161340Y-1044660D01*
X161967Y-1045290D01*
X162750Y-1045500D01*
X163533Y-1045290D01*
X164160Y-1044660D01*
X164473Y-1043715D01*
Y-1039200D01*
G01X167092Y-1045500D02*
X169050Y-1039200D01*
X171008Y-1045500D01*
G01X170303Y-1043295D02*
X167797D01*
G01X173548Y-1045500D02*
Y-1039200D01*
X177152Y-1045500D01*
Y-1039200D01*
G01X51073Y-1049725D02*
X50603Y-1049410D01*
X50055Y-1049200D01*
X49428D01*
X48723Y-1049515D01*
X48175Y-1050040D01*
X47783Y-1050670D01*
X47470Y-1051720D01*
X47392Y-1052665D01*
X47548Y-1053610D01*
X47783Y-1054240D01*
X48253Y-1054870D01*
X48802Y-1055290D01*
X49350Y-1055500D01*
X49898D01*
X50447Y-1055290D01*
X50917Y-1054975D01*
X51308Y-1054555D01*
G01X54710Y-1049200D02*
X56590D01*
G01X55650D02*
Y-1055500D01*
G01X54710D02*
X56590D01*
G01X61950Y-1049200D02*
Y-1055500D01*
G01X60148Y-1049200D02*
X63752D01*
G01X68250Y-1055500D02*
Y-1052665D01*
X66683Y-1049200D01*
G01X69817D02*
X68250Y-1052665D01*
G01X79127Y-1054240D02*
X79597Y-1054975D01*
X80223Y-1055395D01*
X80928Y-1055500D01*
X81555Y-1055395D01*
X82182Y-1054870D01*
X82573Y-1054240D01*
X82652Y-1053610D01*
X82495Y-1052875D01*
X81947Y-1052350D01*
X81398Y-1052140D01*
X80693D01*
G01X81398D02*
X81868Y-1051825D01*
X82260Y-1051300D01*
X82417Y-1050670D01*
X82260Y-1050040D01*
X81868Y-1049515D01*
X81163Y-1049200D01*
X80458Y-1049305D01*
X79753Y-1049725D01*
G01X85427Y-1054240D02*
X85897Y-1054975D01*
X86523Y-1055395D01*
X87228Y-1055500D01*
X87855Y-1055395D01*
X88482Y-1054870D01*
X88873Y-1054240D01*
X88952Y-1053610D01*
X88795Y-1052875D01*
X88247Y-1052350D01*
X87698Y-1052140D01*
X86993D01*
G01X87698D02*
X88168Y-1051825D01*
X88560Y-1051300D01*
X88717Y-1050670D01*
X88560Y-1050040D01*
X88168Y-1049515D01*
X87463Y-1049200D01*
X86758Y-1049305D01*
X86053Y-1049725D01*
G01X91727Y-1054240D02*
X92197Y-1054975D01*
X92823Y-1055395D01*
X93528Y-1055500D01*
X94155Y-1055395D01*
X94782Y-1054870D01*
X95173Y-1054240D01*
X95252Y-1053610D01*
X95095Y-1052875D01*
X94547Y-1052350D01*
X93998Y-1052140D01*
X93293D01*
G01X93998D02*
X94468Y-1051825D01*
X94860Y-1051300D01*
X95017Y-1050670D01*
X94860Y-1050040D01*
X94468Y-1049515D01*
X93763Y-1049200D01*
X93058Y-1049305D01*
X92353Y-1049725D01*
G01X99593Y-1055500D02*
X99750Y-1054135D01*
X99985Y-1052980D01*
X100298Y-1051930D01*
X100690Y-1050775D01*
X101317Y-1049200D01*
X98183D01*
G01X105893Y-1055500D02*
X106050Y-1054135D01*
X106285Y-1052980D01*
X106598Y-1051930D01*
X106990Y-1050775D01*
X107617Y-1049200D01*
X104483D01*
G01X112193Y-1056655D02*
X112507Y-1055290D01*
G01X118650Y-1049200D02*
Y-1055500D01*
G01X116848Y-1049200D02*
X120452D01*
G01X122992Y-1055500D02*
X124950Y-1049200D01*
X126908Y-1055500D01*
G01X126203Y-1053295D02*
X123697D01*
G01X130310Y-1049200D02*
X132190D01*
G01X131250D02*
Y-1055500D01*
G01X130310D02*
X132190D01*
G01X135200Y-1049200D02*
X136297Y-1055500D01*
X137550Y-1049200D01*
X138803Y-1055500D01*
X139900Y-1049200D01*
G01X141892Y-1055500D02*
X143850Y-1049200D01*
X145808Y-1055500D01*
G01X145103Y-1053295D02*
X142597D01*
G01X148348Y-1055500D02*
Y-1049200D01*
X151952Y-1055500D01*
Y-1049200D01*
G01X162358Y-1057600D02*
X161575Y-1056550D01*
X161183Y-1055500D01*
Y-1051300D01*
X161575Y-1050250D01*
X162358Y-1049200D01*
G01X173783Y-1055500D02*
Y-1049200D01*
X175742D01*
X176368Y-1049515D01*
X176760Y-1049935D01*
X176917Y-1050775D01*
X176760Y-1051615D01*
X176290Y-1052140D01*
X175742Y-1052455D01*
X173783D01*
G01X175742D02*
X176917Y-1055500D01*
G01X181650Y-1055710D02*
X181493Y-1055605D01*
Y-1055395D01*
X181650Y-1055290D01*
X181807Y-1055395D01*
Y-1055605D01*
X181650Y-1055710D01*
G01X187950Y-1055500D02*
X187323Y-1055395D01*
X186775Y-1054975D01*
X186305Y-1054345D01*
X185992Y-1053610D01*
X185835Y-1052770D01*
Y-1051930D01*
X185992Y-1051090D01*
X186305Y-1050355D01*
X186775Y-1049725D01*
X187323Y-1049305D01*
X187950Y-1049200D01*
X188577Y-1049305D01*
X189125Y-1049725D01*
X189595Y-1050355D01*
X189908Y-1051090D01*
X190065Y-1051930D01*
Y-1052770D01*
X189908Y-1053610D01*
X189595Y-1054345D01*
X189125Y-1054975D01*
X188577Y-1055395D01*
X187950Y-1055500D01*
G01X194250Y-1055710D02*
X194093Y-1055605D01*
Y-1055395D01*
X194250Y-1055290D01*
X194407Y-1055395D01*
Y-1055605D01*
X194250Y-1055710D01*
G01X202273Y-1049725D02*
X201803Y-1049410D01*
X201255Y-1049200D01*
X200628D01*
X199923Y-1049515D01*
X199375Y-1050040D01*
X198983Y-1050670D01*
X198670Y-1051720D01*
X198592Y-1052665D01*
X198748Y-1053610D01*
X198983Y-1054240D01*
X199453Y-1054870D01*
X200002Y-1055290D01*
X200550Y-1055500D01*
X201098D01*
X201647Y-1055290D01*
X202117Y-1054975D01*
X202508Y-1054555D01*
G01X206850Y-1055710D02*
X206693Y-1055605D01*
Y-1055395D01*
X206850Y-1055290D01*
X207007Y-1055395D01*
Y-1055605D01*
X206850Y-1055710D01*
G01X213542Y-1057600D02*
X214325Y-1056550D01*
X214717Y-1055500D01*
Y-1051300D01*
X214325Y-1050250D01*
X213542Y-1049200D01*
G01X47548Y-1035500D02*
Y-1029200D01*
X51152Y-1035500D01*
Y-1029200D01*
G01X55650Y-1035500D02*
X55023Y-1035395D01*
X54475Y-1034975D01*
X54005Y-1034345D01*
X53692Y-1033610D01*
X53535Y-1032770D01*
Y-1031930D01*
X53692Y-1031090D01*
X54005Y-1030355D01*
X54475Y-1029725D01*
X55023Y-1029305D01*
X55650Y-1029200D01*
X56277Y-1029305D01*
X56825Y-1029725D01*
X57295Y-1030355D01*
X57608Y-1031090D01*
X57765Y-1031930D01*
Y-1032770D01*
X57608Y-1033610D01*
X57295Y-1034345D01*
X56825Y-1034975D01*
X56277Y-1035395D01*
X55650Y-1035500D01*
G01X61950Y-1035710D02*
X61793Y-1035605D01*
Y-1035395D01*
X61950Y-1035290D01*
X62107Y-1035395D01*
Y-1035605D01*
X61950Y-1035710D01*
G01X66762Y-1030250D02*
X67232Y-1029620D01*
X67780Y-1029305D01*
X68407Y-1029200D01*
X69190Y-1029410D01*
X69738Y-1029935D01*
X69895Y-1030565D01*
X69817Y-1031195D01*
X69503Y-1031720D01*
X67937Y-1032770D01*
X67232Y-1033505D01*
X66762Y-1034555D01*
X66605Y-1035500D01*
X69895D01*
G01X74550D02*
Y-1029200D01*
X73610Y-1030460D01*
G01Y-1035500D02*
X75490D01*
G01X80850D02*
Y-1029200D01*
X79910Y-1030460D01*
G01Y-1035500D02*
X81790D01*
G01X86993Y-1036655D02*
X87307Y-1035290D01*
G01X91100Y-1029200D02*
X92197Y-1035500D01*
X93450Y-1029200D01*
X94703Y-1035500D01*
X95800Y-1029200D01*
G01X101317Y-1035500D02*
X98183D01*
Y-1029200D01*
X101317D01*
G01X100063Y-1032245D02*
X98183D01*
G01X104248Y-1035500D02*
Y-1029200D01*
X107852Y-1035500D01*
Y-1029200D01*
G01X110705Y-1035500D02*
Y-1029200D01*
G01X113995D02*
Y-1035500D01*
G01Y-1032350D02*
X110705D01*
G01X116927Y-1029200D02*
Y-1033715D01*
X117240Y-1034660D01*
X117867Y-1035290D01*
X118650Y-1035500D01*
X119433Y-1035290D01*
X120060Y-1034660D01*
X120373Y-1033715D01*
Y-1029200D01*
G01X122992Y-1035500D02*
X124950Y-1029200D01*
X126908Y-1035500D01*
G01X126203Y-1033295D02*
X123697D01*
G01X136062Y-1030250D02*
X136532Y-1029620D01*
X137080Y-1029305D01*
X137707Y-1029200D01*
X138490Y-1029410D01*
X139038Y-1029935D01*
X139195Y-1030565D01*
X139117Y-1031195D01*
X138803Y-1031720D01*
X137237Y-1032770D01*
X136532Y-1033505D01*
X136062Y-1034555D01*
X135905Y-1035500D01*
X139195D01*
G01X142048D02*
Y-1029200D01*
X145652Y-1035500D01*
Y-1029200D01*
G01X148427Y-1035500D02*
Y-1029200D01*
X149993D01*
X150620Y-1029515D01*
X151090Y-1029935D01*
X151482Y-1030565D01*
X151795Y-1031300D01*
X151873Y-1032350D01*
X151795Y-1033400D01*
X151482Y-1034135D01*
X151090Y-1034765D01*
X150620Y-1035185D01*
X149993Y-1035500D01*
X148427D01*
G01X161183D02*
Y-1029200D01*
X163142D01*
X163768Y-1029515D01*
X164160Y-1029935D01*
X164317Y-1030775D01*
X164160Y-1031615D01*
X163690Y-1032140D01*
X163142Y-1032455D01*
X161183D01*
G01X163142D02*
X164317Y-1035500D01*
G01X167327D02*
Y-1029200D01*
X168893D01*
X169520Y-1029515D01*
X169990Y-1029935D01*
X170382Y-1030565D01*
X170695Y-1031300D01*
X170773Y-1032350D01*
X170695Y-1033400D01*
X170382Y-1034135D01*
X169990Y-1034765D01*
X169520Y-1035185D01*
X168893Y-1035500D01*
X167327D01*
G01X175350Y-1035710D02*
X175193Y-1035605D01*
Y-1035395D01*
X175350Y-1035290D01*
X175507Y-1035395D01*
Y-1035605D01*
X175350Y-1035710D01*
G01X254500Y-1037500D02*
Y-1029500D01*
X256900D01*
X257700Y-1029900D01*
X258300Y-1030833D01*
X258500Y-1031900D01*
X258300Y-1032967D01*
X257800Y-1033767D01*
X256900Y-1034167D01*
X254500D01*
G01X262000Y-1037500D02*
X264500Y-1029500D01*
X267000Y-1037500D01*
G01X266100Y-1034700D02*
X262900D01*
G01X270400Y-1036434D02*
X271200Y-1037100D01*
X272100Y-1037500D01*
X272900D01*
X273700Y-1037100D01*
X274300Y-1036434D01*
X274600Y-1035500D01*
X274400Y-1034567D01*
X273900Y-1033767D01*
X273000Y-1033233D01*
X271800Y-1032967D01*
X271100Y-1032433D01*
X270800Y-1031500D01*
X271000Y-1030567D01*
X271500Y-1029900D01*
X272200Y-1029500D01*
X272900D01*
X273600Y-1029767D01*
X274200Y-1030433D01*
G01X280500Y-1029500D02*
Y-1037500D01*
G01X278200Y-1029500D02*
X282800D01*
G01X287200Y-1034833D02*
X289800D01*
G01X297300Y-1033233D02*
X297700Y-1032833D01*
X298000Y-1032167D01*
X298200Y-1031233D01*
X298000Y-1030433D01*
X297600Y-1029900D01*
X296900Y-1029500D01*
X294200D01*
Y-1037500D01*
X297500D01*
X298200Y-1036967D01*
X298600Y-1036167D01*
X298800Y-1035233D01*
X298600Y-1034300D01*
X298000Y-1033500D01*
X297300Y-1033233D01*
X294200D01*
G01X304500Y-1037500D02*
X303700Y-1037367D01*
X303000Y-1036833D01*
X302400Y-1036033D01*
X302000Y-1035100D01*
X301800Y-1034033D01*
Y-1032967D01*
X302000Y-1031900D01*
X302400Y-1030967D01*
X303000Y-1030167D01*
X303700Y-1029633D01*
X304500Y-1029500D01*
X305300Y-1029633D01*
X306000Y-1030167D01*
X306600Y-1030967D01*
X307000Y-1031900D01*
X307200Y-1032967D01*
Y-1034033D01*
X307000Y-1035100D01*
X306600Y-1036033D01*
X306000Y-1036833D01*
X305300Y-1037367D01*
X304500Y-1037500D01*
G01X312500Y-1029500D02*
Y-1037500D01*
G01X310200Y-1029500D02*
X314800D01*
G01X243000Y-1004500D02*
Y-1012500D01*
X247000D01*
G01X254800D02*
Y-1007167D01*
G01Y-1008100D02*
X254400Y-1007567D01*
X253800Y-1007300D01*
X253100Y-1007167D01*
X252400Y-1007433D01*
X251800Y-1007967D01*
X251400Y-1008767D01*
X251200Y-1009833D01*
X251400Y-1010900D01*
X251800Y-1011700D01*
X252400Y-1012233D01*
X253100Y-1012500D01*
X253800Y-1012367D01*
X254400Y-1011967D01*
X254800Y-1011434D01*
G01X258900Y-1014900D02*
X259500Y-1015167D01*
X260300Y-1014900D01*
X260800Y-1014367D01*
X261200Y-1013700D01*
X261800Y-1011567D01*
X263100Y-1007167D01*
G01X259900D02*
X261800Y-1011567D01*
G01X267500Y-1008900D02*
X270700D01*
X270400Y-1007967D01*
X269900Y-1007433D01*
X269200Y-1007167D01*
X268500Y-1007300D01*
X267900Y-1007700D01*
X267500Y-1008633D01*
X267300Y-1009434D01*
Y-1010233D01*
X267500Y-1011033D01*
X268000Y-1011833D01*
X268600Y-1012367D01*
X269300Y-1012500D01*
X270000Y-1012233D01*
X270700Y-1011434D01*
G01X275600Y-1012500D02*
Y-1007167D01*
G01Y-1008233D02*
X276100Y-1007700D01*
X276600Y-1007300D01*
X277300Y-1007167D01*
X277800Y-1007300D01*
X278400Y-1007700D01*
G01X262100Y-1054500D02*
X265900D01*
X262100Y-1062500D01*
X265900D01*
G01X272000Y-1057167D02*
Y-1062500D01*
G01Y-1055033D02*
X271800Y-1054900D01*
Y-1054633D01*
X272000Y-1054500D01*
X272200Y-1054633D01*
Y-1054900D01*
X272000Y-1055033D01*
G01X278700Y-1059833D02*
X281300D01*
G01X286200Y-1065167D02*
Y-1057167D01*
G01Y-1058367D02*
X286700Y-1057700D01*
X287200Y-1057300D01*
X288000Y-1057167D01*
X288700Y-1057300D01*
X289400Y-1057967D01*
X289700Y-1058900D01*
X289800Y-1059833D01*
X289700Y-1060767D01*
X289400Y-1061700D01*
X288800Y-1062233D01*
X288000Y-1062500D01*
X287300Y-1062367D01*
X286600Y-1061967D01*
X286200Y-1061434D01*
G01X296000Y-1057167D02*
Y-1062500D01*
G01Y-1055033D02*
X295800Y-1054900D01*
Y-1054633D01*
X296000Y-1054500D01*
X296200Y-1054633D01*
Y-1054900D01*
X296000Y-1055033D01*
G01X302300Y-1062500D02*
Y-1057167D01*
G01Y-1058500D02*
X302700Y-1057833D01*
X303300Y-1057300D01*
X304100Y-1057167D01*
X304800Y-1057300D01*
X305400Y-1057833D01*
X305700Y-1058767D01*
Y-1062500D01*
G01X310600Y-1064500D02*
X311300Y-1065033D01*
X312100Y-1065167D01*
X312800Y-1065033D01*
X313400Y-1064367D01*
X313800Y-1063433D01*
Y-1057167D01*
G01Y-1058233D02*
X313400Y-1057700D01*
X312800Y-1057300D01*
X312100Y-1057167D01*
X311300Y-1057433D01*
X310800Y-1057967D01*
X310400Y-1058900D01*
X310200Y-1059833D01*
X310300Y-1060633D01*
X310700Y-1061567D01*
X311300Y-1062233D01*
X312100Y-1062500D01*
X312700Y-1062367D01*
X313400Y-1061833D01*
X313800Y-1061300D01*
G01X369600Y-1055833D02*
X370200Y-1055033D01*
X370900Y-1054633D01*
X371700Y-1054500D01*
X372700Y-1054767D01*
X373400Y-1055433D01*
X373600Y-1056233D01*
X373500Y-1057034D01*
X373100Y-1057700D01*
X371100Y-1059033D01*
X370200Y-1059967D01*
X369600Y-1061300D01*
X369400Y-1062500D01*
X373600D01*
G01X379500Y-1054500D02*
X378700Y-1054767D01*
X378100Y-1055433D01*
X377700Y-1056233D01*
X377400Y-1057300D01*
X377300Y-1058500D01*
X377400Y-1059700D01*
X377700Y-1060767D01*
X378100Y-1061567D01*
X378700Y-1062233D01*
X379500Y-1062500D01*
X380300Y-1062233D01*
X380900Y-1061567D01*
X381300Y-1060767D01*
X381600Y-1059700D01*
X381700Y-1058500D01*
X381600Y-1057300D01*
X381300Y-1056233D01*
X380900Y-1055433D01*
X380300Y-1054767D01*
X379500Y-1054500D01*
G01X385600Y-1055833D02*
X386200Y-1055033D01*
X386900Y-1054633D01*
X387700Y-1054500D01*
X388700Y-1054767D01*
X389400Y-1055433D01*
X389600Y-1056233D01*
X389500Y-1057034D01*
X389100Y-1057700D01*
X387100Y-1059033D01*
X386200Y-1059967D01*
X385600Y-1061300D01*
X385400Y-1062500D01*
X389600D01*
G01X393600Y-1055833D02*
X394200Y-1055033D01*
X394900Y-1054633D01*
X395700Y-1054500D01*
X396700Y-1054767D01*
X397400Y-1055433D01*
X397600Y-1056233D01*
X397500Y-1057034D01*
X397100Y-1057700D01*
X395100Y-1059033D01*
X394200Y-1059967D01*
X393600Y-1061300D01*
X393400Y-1062500D01*
X397600D01*
G01X401700Y-1062767D02*
X405300Y-1054500D01*
G01X411500Y-1062500D02*
Y-1054500D01*
X410300Y-1056100D01*
G01Y-1062500D02*
X412700D01*
G01X417600Y-1055833D02*
X418200Y-1055033D01*
X418900Y-1054633D01*
X419700Y-1054500D01*
X420700Y-1054767D01*
X421400Y-1055433D01*
X421600Y-1056233D01*
X421500Y-1057034D01*
X421100Y-1057700D01*
X419100Y-1059033D01*
X418200Y-1059967D01*
X417600Y-1061300D01*
X417400Y-1062500D01*
X421600D01*
G01X425700Y-1062767D02*
X429300Y-1054500D01*
G01X435500Y-1062500D02*
Y-1054500D01*
X434300Y-1056100D01*
G01Y-1062500D02*
X436700D01*
G01X441300Y-1060900D02*
X441900Y-1061833D01*
X442700Y-1062367D01*
X443600Y-1062500D01*
X444400Y-1062367D01*
X445200Y-1061700D01*
X445700Y-1060900D01*
X445800Y-1060100D01*
X445600Y-1059167D01*
X444900Y-1058500D01*
X444200Y-1058233D01*
X443300D01*
G01X444200D02*
X444800Y-1057833D01*
X445300Y-1057167D01*
X445500Y-1056367D01*
X445300Y-1055567D01*
X444800Y-1054900D01*
X443900Y-1054500D01*
X443000Y-1054633D01*
X442100Y-1055167D01*
G01X369300Y-1040000D02*
Y-1032000D01*
X371300D01*
X372100Y-1032400D01*
X372700Y-1032933D01*
X373200Y-1033733D01*
X373600Y-1034667D01*
X373700Y-1036000D01*
X373600Y-1037333D01*
X373200Y-1038267D01*
X372700Y-1039067D01*
X372100Y-1039600D01*
X371300Y-1040000D01*
X369300D01*
G01X377000D02*
X379500Y-1032000D01*
X382000Y-1040000D01*
G01X381100Y-1037200D02*
X377900D01*
G01X385600Y-1040000D02*
Y-1032000D01*
X389400D01*
G01X388000Y-1035867D02*
X385600D01*
G01X395500Y-1032000D02*
X394700Y-1032267D01*
X394100Y-1032933D01*
X393700Y-1033733D01*
X393400Y-1034800D01*
X393300Y-1036000D01*
X393400Y-1037200D01*
X393700Y-1038267D01*
X394100Y-1039067D01*
X394700Y-1039733D01*
X395500Y-1040000D01*
X396300Y-1039733D01*
X396900Y-1039067D01*
X397300Y-1038267D01*
X397600Y-1037200D01*
X397700Y-1036000D01*
X397600Y-1034800D01*
X397300Y-1033733D01*
X396900Y-1032933D01*
X396300Y-1032267D01*
X395500Y-1032000D01*
G01X403500D02*
Y-1040000D01*
G01X401200Y-1032000D02*
X405800D01*
G01X409500Y-1040000D02*
Y-1032000D01*
X411900D01*
X412700Y-1032400D01*
X413300Y-1033333D01*
X413500Y-1034400D01*
X413300Y-1035467D01*
X412800Y-1036267D01*
X411900Y-1036667D01*
X409500D01*
G01X420300Y-1035733D02*
X420700Y-1035333D01*
X421000Y-1034667D01*
X421200Y-1033733D01*
X421000Y-1032933D01*
X420600Y-1032400D01*
X419900Y-1032000D01*
X417200D01*
Y-1040000D01*
X420500D01*
X421200Y-1039467D01*
X421600Y-1038667D01*
X421800Y-1037733D01*
X421600Y-1036800D01*
X421000Y-1036000D01*
X420300Y-1035733D01*
X417200D01*
G01X427500Y-1040000D02*
Y-1032000D01*
X426300Y-1033600D01*
G01Y-1040000D02*
X428700D01*
G01X433000D02*
X435500Y-1032000D01*
X438000Y-1040000D01*
G01X437100Y-1037200D02*
X433900D01*
G01X441600Y-1040000D02*
Y-1032000D01*
X445400D01*
G01X444000Y-1035867D02*
X441600D01*
G01X451500Y-1032000D02*
X450700Y-1032267D01*
X450100Y-1032933D01*
X449700Y-1033733D01*
X449400Y-1034800D01*
X449300Y-1036000D01*
X449400Y-1037200D01*
X449700Y-1038267D01*
X450100Y-1039067D01*
X450700Y-1039733D01*
X451500Y-1040000D01*
X452300Y-1039733D01*
X452900Y-1039067D01*
X453300Y-1038267D01*
X453600Y-1037200D01*
X453700Y-1036000D01*
X453600Y-1034800D01*
X453300Y-1033733D01*
X452900Y-1032933D01*
X452300Y-1032267D01*
X451500Y-1032000D01*
G01X389600Y-1012500D02*
Y-1004500D01*
X393400D01*
G01X392000Y-1008367D02*
X389600D01*
G01X399500Y-1004500D02*
X398700Y-1004767D01*
X398100Y-1005433D01*
X397700Y-1006233D01*
X397400Y-1007300D01*
X397300Y-1008500D01*
X397400Y-1009700D01*
X397700Y-1010767D01*
X398100Y-1011567D01*
X398700Y-1012233D01*
X399500Y-1012500D01*
X400300Y-1012233D01*
X400900Y-1011567D01*
X401300Y-1010767D01*
X401600Y-1009700D01*
X401700Y-1008500D01*
X401600Y-1007300D01*
X401300Y-1006233D01*
X400900Y-1005433D01*
X400300Y-1004767D01*
X399500Y-1004500D01*
G01X407500D02*
Y-1012500D01*
G01X405200Y-1004500D02*
X409800D01*
G01X412500Y-1015167D02*
X418500D01*
G01X421500Y-1012500D02*
Y-1004500D01*
X423900D01*
X424700Y-1004900D01*
X425300Y-1005833D01*
X425500Y-1006900D01*
X425300Y-1007967D01*
X424800Y-1008767D01*
X423900Y-1009167D01*
X421500D01*
G01X429300Y-1012500D02*
Y-1004500D01*
X431300D01*
X432100Y-1004900D01*
X432700Y-1005433D01*
X433200Y-1006233D01*
X433600Y-1007167D01*
X433700Y-1008500D01*
X433600Y-1009833D01*
X433200Y-1010767D01*
X432700Y-1011567D01*
X432100Y-1012100D01*
X431300Y-1012500D01*
X429300D01*
G01X440300Y-1008233D02*
X440700Y-1007833D01*
X441000Y-1007167D01*
X441200Y-1006233D01*
X441000Y-1005433D01*
X440600Y-1004900D01*
X439900Y-1004500D01*
X437200D01*
Y-1012500D01*
X440500D01*
X441200Y-1011967D01*
X441600Y-1011167D01*
X441800Y-1010233D01*
X441600Y-1009300D01*
X441000Y-1008500D01*
X440300Y-1008233D01*
X437200D01*
G01X444500Y-1015167D02*
X450500D01*
G01X456300Y-1008233D02*
X456700Y-1007833D01*
X457000Y-1007167D01*
X457200Y-1006233D01*
X457000Y-1005433D01*
X456600Y-1004900D01*
X455900Y-1004500D01*
X453200D01*
Y-1012500D01*
X456500D01*
X457200Y-1011967D01*
X457600Y-1011167D01*
X457800Y-1010233D01*
X457600Y-1009300D01*
X457000Y-1008500D01*
X456300Y-1008233D01*
X453200D01*
G01X461300Y-1012500D02*
Y-1004500D01*
X463300D01*
X464100Y-1004900D01*
X464700Y-1005433D01*
X465200Y-1006233D01*
X465600Y-1007167D01*
X465700Y-1008500D01*
X465600Y-1009833D01*
X465200Y-1010767D01*
X464700Y-1011567D01*
X464100Y-1012100D01*
X463300Y-1012500D01*
X461300D01*
G01X468500Y-1015167D02*
X474500D01*
G01X480100Y-1008500D02*
X482100D01*
Y-1010900D01*
X481500Y-1011700D01*
X480800Y-1012233D01*
X479800Y-1012500D01*
X478800Y-1012233D01*
X478100Y-1011700D01*
X477500Y-1010900D01*
X477100Y-1009967D01*
X476900Y-1008900D01*
Y-1007967D01*
X477100Y-1007167D01*
X477500Y-1006233D01*
X478100Y-1005433D01*
X478700Y-1004900D01*
X479500Y-1004500D01*
X480200D01*
X481000Y-1004767D01*
X481600Y-1005300D01*
G01X485500Y-1012500D02*
Y-1004500D01*
X487900D01*
X488700Y-1004900D01*
X489300Y-1005833D01*
X489500Y-1006900D01*
X489300Y-1007967D01*
X488800Y-1008767D01*
X487900Y-1009167D01*
X485500D01*
G01X493300Y-1004500D02*
Y-1010233D01*
X493700Y-1011434D01*
X494500Y-1012233D01*
X495500Y-1012500D01*
X496500Y-1012233D01*
X497300Y-1011434D01*
X497700Y-1010233D01*
Y-1004500D01*
G01X458000Y-1065500D02*
Y-1057500D01*
X456800Y-1059100D01*
G01Y-1065500D02*
X459200D01*
G01X464100Y-1062167D02*
X464800Y-1061233D01*
X465400Y-1060700D01*
X466200Y-1060433D01*
X466900Y-1060700D01*
X467400Y-1061233D01*
X467800Y-1062033D01*
X467900Y-1062967D01*
X467800Y-1063767D01*
X467400Y-1064567D01*
X466800Y-1065233D01*
X466100Y-1065500D01*
X465300Y-1065233D01*
X464600Y-1064434D01*
X464200Y-1063233D01*
X464100Y-1061900D01*
X464300Y-1060167D01*
X464600Y-1059233D01*
X465100Y-1058300D01*
X465800Y-1057633D01*
X466500Y-1057500D01*
X467200Y-1057767D01*
X467700Y-1058433D01*
G01X474000Y-1065767D02*
X473800Y-1065633D01*
Y-1065367D01*
X474000Y-1065233D01*
X474200Y-1065367D01*
Y-1065633D01*
X474000Y-1065767D01*
G01X480100Y-1062167D02*
X480800Y-1061233D01*
X481400Y-1060700D01*
X482200Y-1060433D01*
X482900Y-1060700D01*
X483400Y-1061233D01*
X483800Y-1062033D01*
X483900Y-1062967D01*
X483800Y-1063767D01*
X483400Y-1064567D01*
X482800Y-1065233D01*
X482100Y-1065500D01*
X481300Y-1065233D01*
X480600Y-1064434D01*
X480200Y-1063233D01*
X480100Y-1061900D01*
X480300Y-1060167D01*
X480600Y-1059233D01*
X481100Y-1058300D01*
X481800Y-1057633D01*
X482500Y-1057500D01*
X483200Y-1057767D01*
X483700Y-1058433D01*
G01X503000Y-1065500D02*
Y-1057500D01*
X501800Y-1059100D01*
G01Y-1065500D02*
X504200D01*
G01X510800D02*
X511000Y-1063767D01*
X511300Y-1062300D01*
X511700Y-1060967D01*
X512200Y-1059500D01*
X513000Y-1057500D01*
X509000D01*
G01X519000Y-1065767D02*
X518800Y-1065633D01*
Y-1065367D01*
X519000Y-1065233D01*
X519200Y-1065367D01*
Y-1065633D01*
X519000Y-1065767D01*
G01X525100Y-1058833D02*
X525700Y-1058033D01*
X526400Y-1057633D01*
X527200Y-1057500D01*
X528200Y-1057767D01*
X528900Y-1058433D01*
X529100Y-1059233D01*
X529000Y-1060034D01*
X528600Y-1060700D01*
X526600Y-1062033D01*
X525700Y-1062967D01*
X525100Y-1064300D01*
X524900Y-1065500D01*
X529100D01*
G01X523100Y-1040500D02*
Y-1032500D01*
X526900D01*
G01X525500Y-1036367D02*
X523100D01*
G54D27*
X604701Y245500D03*
X605201Y302500D03*
X639201Y277500D03*
X628201Y282000D03*
X635201Y284500D03*
X639701Y298000D03*
Y293500D03*
X641617Y308500D03*
X668701Y269000D03*
X664701Y292500D03*
Y296500D03*
Y280500D03*
Y284500D03*
Y288500D03*
X664617Y308500D03*
X707517Y212000D03*
X692201Y251000D03*
X697701Y306500D03*
X693201Y302000D03*
X1024617Y208500D03*
X1070617Y245500D03*
X1094617Y247500D03*
Y251500D03*
X1096117Y297500D03*
Y289500D03*
X1098117Y285000D03*
X1096117Y293500D03*
X1124117Y263500D03*
Y278500D03*
Y283000D03*
Y287500D03*
Y292000D03*
X1627017Y146000D03*
Y142500D03*
Y153500D03*
X1661117Y138000D03*
X1678017Y149500D03*
X1736017Y181000D03*
Y186500D03*
X1767017Y184000D03*
G54D45*
X822087Y88484D03*
Y313484D03*
X940197Y88484D03*
Y313484D03*
G54D36*
X706600Y234799D03*
Y222201D03*
X1036600Y300701D03*
Y313299D03*
G54D18*
X434100Y173116D03*
Y217516D03*
X438100D03*
X607684Y249516D03*
X612684Y302516D03*
X616684D03*
X635184Y277516D03*
X680100Y249516D03*
X676100D03*
X672184D03*
X688184D03*
X684184D03*
X699684D03*
X1127100Y255516D03*
Y247516D03*
X1149600Y238016D03*
X1145600D03*
X1140100Y246516D03*
X1163000Y344516D03*
X1328100Y153516D03*
X1324100Y197916D03*
X1328100D03*
X1645277Y127490D03*
G54D28*
X610129Y276000D03*
G54D37*
X691214Y278000D03*
X1071070Y274000D03*
G54D19*
X434100Y176083D03*
Y220483D03*
X438100D03*
X607684Y252483D03*
X612684Y305483D03*
X616684D03*
X635184Y280483D03*
X680100Y252483D03*
X676100D03*
X672184D03*
X688184D03*
X684184D03*
X699684D03*
X1127100Y258483D03*
Y250483D03*
X1149600Y240983D03*
X1145600D03*
X1140100Y249483D03*
X1163000Y347483D03*
X1328100Y156483D03*
X1324100Y200883D03*
X1328100D03*
X1645277Y130457D03*
G54D46*
X825900Y362200D03*
X866400Y382200D03*
X906900Y362200D03*
G54D29*
X593198Y265173D03*
X620170D03*
Y286827D03*
X593198D03*
X1142114Y265173D03*
Y286827D03*
X1169086Y265173D03*
Y286827D03*
G54D38*
X683134Y267170D03*
Y269140D03*
Y271110D03*
Y273080D03*
Y275050D03*
Y277020D03*
Y278980D03*
Y280950D03*
Y282920D03*
Y284890D03*
Y286860D03*
Y288830D03*
X714234Y269140D03*
Y267170D03*
Y288830D03*
Y286860D03*
Y284890D03*
Y282920D03*
Y280950D03*
Y278980D03*
Y277020D03*
Y275050D03*
Y273080D03*
Y271110D03*
X1048050Y263170D03*
Y265140D03*
Y267110D03*
Y269080D03*
Y271050D03*
Y273020D03*
Y274980D03*
Y276950D03*
Y278920D03*
Y280890D03*
Y282860D03*
Y284830D03*
X1079150Y269080D03*
Y267110D03*
Y265140D03*
Y263170D03*
Y284830D03*
Y282860D03*
Y280890D03*
Y278920D03*
Y276950D03*
Y274980D03*
Y273020D03*
Y271050D03*
G54D47*
X825900Y382200D03*
Y372200D03*
X866400Y362200D03*
Y372200D03*
X906900Y382200D03*
Y372200D03*
G54D48*
X1128224Y358760D03*
X1118776D03*
X1128224Y366240D03*
X1118776D03*
Y362500D03*
X1758824Y183760D03*
Y191240D03*
X1749376D03*
Y187500D03*
Y183760D03*
G54D39*
X709514Y264420D03*
X707544D03*
X705574D03*
X703604D03*
X697704D03*
X695734D03*
X693764D03*
X691794D03*
X689824D03*
X687854D03*
X685884D03*
Y291580D03*
X687854D03*
X689824D03*
X691794D03*
X693764D03*
X695734D03*
X697704D03*
X703604D03*
X705574D03*
X707544D03*
X709514D03*
X711484Y264420D03*
Y291580D03*
X1072460Y260420D03*
X1070490D03*
X1068520D03*
X1066550D03*
X1064580D03*
X1058680D03*
X1056710D03*
X1054740D03*
X1052770D03*
X1050800D03*
Y287580D03*
X1052770D03*
X1054740D03*
X1056710D03*
X1058680D03*
X1064580D03*
X1066550D03*
X1068520D03*
X1070490D03*
X1072460D03*
X1076400Y260420D03*
X1074430D03*
Y287580D03*
X1076400D03*
G54D49*
X1152155Y276000D03*
M02*
